(kicad_pcb
	(version 20221018)
	(generator pcbnew)
	(general
    (thickness 1.562)
  )
	(paper "A4")
	(title_block
    (title "Thunderbolt PCIe Adaper")
    (date "2024-07-09")
    (rev "1.0.3")
    (comment 1 "www.antmicro.com")
    (comment 2 "Antmicro Ltd.")
		(comment 9 "footprint 10 of 271 (U4), pads 194-293 of 337")
	)
	(layers
    (0 "F.Cu" signal)
    (1 "In1.Cu" signal)
    (2 "In2.Cu" signal)
    (3 "In3.Cu" signal)
    (4 "In4.Cu" signal)
    (31 "B.Cu" signal)
    (32 "B.Adhes" user "B.Adhesive")
    (33 "F.Adhes" user "F.Adhesive")
    (34 "B.Paste" user)
    (35 "F.Paste" user)
    (36 "B.SilkS" user "B.Silkscreen")
    (37 "F.SilkS" user "F.Silkscreen")
    (38 "B.Mask" user)
    (39 "F.Mask" user)
    (40 "Dwgs.User" user "User.Drawings")
    (41 "Cmts.User" user "User.Comments")
    (42 "Eco1.User" user "User.Eco1")
    (43 "Eco2.User" user "User.Eco2")
    (44 "Edge.Cuts" user)
    (45 "Margin" user)
    (46 "B.CrtYd" user "B.Courtyard")
    (47 "F.CrtYd" user "F.Courtyard")
    (48 "B.Fab" user)
    (49 "F.Fab" user)
  )
	(footprint "antmicro-footprints:JHL6340SLLSQ"
    (layer "F.Cu")
    (at 134.8 79.85 -90)
    (property "Author" "Antmicro")
    (property "License" "Apache-2.0")
    (property "MPN" "JHL6340SLLSQ")
    (property "Manufacturer" "Intel")
    (property "Sheetfile" "tb-power.kicad_sch")
    (property "Sheetname" "Thunderbolt Controller - Power")
    (property "ki_description" "Thunderbolt™ 3 Controller, I/O")
    (property "ki_keywords" "IC")
    (attr smd)
    (fp_text reference "U4" (at -4.666 -6.17 -90 unlocked) (layer "F.SilkS")
        (effects (font (size 0.7 0.7) (thickness 0.15)))
    )
    (fp_text value "JHL6340SLLSQ" (at 0 6.4 -90 unlocked) (layer "F.Fab")
        (effects (font (size 0.7 0.7) (thickness 0.15)))
    )
    (pad "L1" smd oval (at -5.06 -0.46) (size 0.1578 0.3302) (layers "F.Cu" "F.Paste" "F.Mask")
      (net 253 "unconnected-(U4C-DPSRC_ML2_N-PadL1)") (pinfunction "DPSRC_ML2_N") (pintype "output+no_connect"))
    (pad "L2" smd circle (at -4.6 -0.46 270) (size 0.254 0.254) (layers "F.Cu" "F.Paste" "F.Mask")
      (net 254 "unconnected-(U4C-DPSRC_ML2_P-PadL2)") (pinfunction "DPSRC_ML2_P") (pintype "output+no_connect"))
    (pad "L4" smd circle (at -3.9 -0.65 270) (size 0.254 0.254) (layers "F.Cu" "F.Paste" "F.Mask")
      (net 43 "PCIE_PWRGD") (pinfunction "PERST_N") (pintype "input"))
    (pad "L5" smd circle (at -3.25 -0.65 270) (size 0.254 0.254) (layers "F.Cu" "F.Paste" "F.Mask")
      (net 1 "GND") (pinfunction "VSS_ANA") (pintype "passive"))
    (pad "L6" smd circle (at -2.6 -0.65 270) (size 0.254 0.254) (layers "F.Cu" "F.Paste" "F.Mask")
      (net 106 "Net-(C53-Pad2)") (pinfunction "VCC0P9_ANA_DPSRC") (pintype "power_in"))
    (pad "L8" smd circle (at -1.95 -0.65 270) (size 0.254 0.254) (layers "F.Cu" "F.Paste" "F.Mask")
      (net 106 "Net-(C53-Pad2)") (pinfunction "VCC0P9_DP") (pintype "passive"))
    (pad "L9" smd circle (at -1.3 -0.65 270) (size 0.254 0.254) (layers "F.Cu" "F.Paste" "F.Mask")
      (net 112 "Net-(U4A-VCC0P9_SVR_SENSE)") (pinfunction "VCC0P9_SVR") (pintype "power_in"))
    (pad "L11" smd circle (at -0.65 -0.65 270) (size 0.254 0.254) (layers "F.Cu" "F.Paste" "F.Mask")
      (net 106 "Net-(C53-Pad2)") (pinfunction "VCC0P9_DP") (pintype "power_in"))
    (pad "L12" smd circle (at 0 -0.65 270) (size 0.254 0.254) (layers "F.Cu" "F.Paste" "F.Mask")
      (net 106 "Net-(C53-Pad2)") (pinfunction "VCC0P9_DP") (pintype "passive"))
    (pad "L13" smd circle (at 0.65 -0.65 270) (size 0.254 0.254) (layers "F.Cu" "F.Paste" "F.Mask")
      (net 1 "GND") (pinfunction "VSS") (pintype "passive"))
    (pad "L15" smd circle (at 1.3 -0.65 270) (size 0.254 0.254) (layers "F.Cu" "F.Paste" "F.Mask")
      (net 1 "GND") (pinfunction "FUSE_VQPS_64") (pintype "passive"))
    (pad "L16" smd circle (at 1.95 -0.65 270) (size 0.254 0.254) (layers "F.Cu" "F.Paste" "F.Mask")
      (net 109 "Net-(U4A-VCC3P3_ANA_PCIE)") (pinfunction "VCC3P3_ANA_PCIE") (pintype "power_in"))
    (pad "L18" smd circle (at 2.6 -0.65 270) (size 0.254 0.254) (layers "F.Cu" "F.Paste" "F.Mask")
      (net 108 "Net-(C56-Pad2)") (pinfunction "VCC0P9_ANA_PCIE_2") (pintype "power_in"))
    (pad "L19" smd circle (at 3.25 -0.65 270) (size 0.254 0.254) (layers "F.Cu" "F.Paste" "F.Mask")
      (net 108 "Net-(C56-Pad2)") (pinfunction "VCC0P9_ANA_PCIE_1") (pintype "power_in"))
    (pad "L20" smd circle (at 3.9 -0.65 270) (size 0.254 0.254) (layers "F.Cu" "F.Paste" "F.Mask")
      (net 1 "GND") (pinfunction "VSS_ANA") (pintype "passive"))
    (pad "L22" smd circle (at 4.6 -0.46 270) (size 0.254 0.254) (layers "F.Cu" "F.Paste" "F.Mask")
      (net 1 "GND") (pinfunction "VSS_ANA") (pintype "passive"))
    (pad "L23" smd oval (at 5.06 -0.46) (size 0.1578 0.3302) (layers "F.Cu" "F.Paste" "F.Mask")
      (net 1 "GND") (pinfunction "VSS_ANA") (pintype "passive"))
    (pad "M1" smd oval (at -5.06 0) (size 0.1578 0.3302) (layers "F.Cu" "F.Paste" "F.Mask")
      (net 1 "GND") (pinfunction "VSS_ANA") (pintype "passive"))
    (pad "M2" smd circle (at -4.6 0 270) (size 0.254 0.254) (layers "F.Cu" "F.Paste" "F.Mask")
      (net 1 "GND") (pinfunction "VSS_ANA") (pintype "passive"))
    (pad "M4" smd circle (at -3.9 0 270) (size 0.254 0.254) (layers "F.Cu" "F.Paste" "F.Mask")
      (net 58 "HPD") (pinfunction "PA_DPSRC_HPD") (pintype "input"))
    (pad "M5" smd circle (at -3.25 0 270) (size 0.254 0.254) (layers "F.Cu" "F.Paste" "F.Mask")
      (net 1 "GND") (pinfunction "VSS_ANA") (pintype "passive"))
    (pad "M6" smd circle (at -2.6 0 270) (size 0.254 0.254) (layers "F.Cu" "F.Paste" "F.Mask")
      (net 106 "Net-(C53-Pad2)") (pinfunction "VCC0P9_ANA_DPSRC") (pintype "passive"))
    (pad "M8" smd circle (at -1.95 0 270) (size 0.254 0.254) (layers "F.Cu" "F.Paste" "F.Mask")
      (net 106 "Net-(C53-Pad2)") (pinfunction "VCC0P9_DP") (pintype "passive"))
    (pad "M9" smd circle (at -1.3 0 270) (size 0.254 0.254) (layers "F.Cu" "F.Paste" "F.Mask")
      (net 112 "Net-(U4A-VCC0P9_SVR_SENSE)") (pinfunction "VCC0P9_SVR") (pintype "passive"))
    (pad "M11" smd circle (at -0.65 0 270) (size 0.254 0.254) (layers "F.Cu" "F.Paste" "F.Mask")
      (net 1 "GND") (pinfunction "VSS") (pintype "passive"))
    (pad "M12" smd circle (at 0 0 270) (size 0.254 0.254) (layers "F.Cu" "F.Paste" "F.Mask")
      (net 1 "GND") (pinfunction "VSS") (pintype "passive"))
    (pad "M13" smd circle (at 0.65 0 270) (size 0.254 0.254) (layers "F.Cu" "F.Paste" "F.Mask")
      (net 108 "Net-(C56-Pad2)") (pinfunction "VCC0P9_PCIE") (pintype "power_in"))
    (pad "M15" smd circle (at 1.3 0 270) (size 0.254 0.254) (layers "F.Cu" "F.Paste" "F.Mask")
      (net 108 "Net-(C56-Pad2)") (pinfunction "VCC0P9_PCIE") (pintype "passive"))
    (pad "M16" smd circle (at 1.95 0 270) (size 0.254 0.254) (layers "F.Cu" "F.Paste" "F.Mask")
      (net 108 "Net-(C56-Pad2)") (pinfunction "VCC0P9_PCIE") (pintype "passive"))
    (pad "M18" smd circle (at 2.6 0 270) (size 0.254 0.254) (layers "F.Cu" "F.Paste" "F.Mask")
      (net 108 "Net-(C56-Pad2)") (pinfunction "VCC0P9_ANA_PCIE_2") (pintype "passive"))
    (pad "M19" smd circle (at 3.25 0 270) (size 0.254 0.254) (layers "F.Cu" "F.Paste" "F.Mask")
      (net 1 "GND") (pinfunction "VSS_ANA") (pintype "passive"))
    (pad "M20" smd circle (at 3.9 0 270) (size 0.254 0.254) (layers "F.Cu" "F.Paste" "F.Mask")
      (net 1 "GND") (pinfunction "VSS_ANA") (pintype "passive"))
    (pad "M22" smd circle (at 4.6 0 270) (size 0.254 0.254) (layers "F.Cu" "F.Paste" "F.Mask")
      (net 51 "PCIE_RX2_N") (pinfunction "PCIE_RX2_N") (pintype "input"))
    (pad "M23" smd oval (at 5.06 0) (size 0.1578 0.3302) (layers "F.Cu" "F.Paste" "F.Mask")
      (net 50 "PCIE_RX2_P") (pinfunction "PCIE_RX2_P") (pintype "input"))
    (pad "N1" smd oval (at -5.06 0.46) (size 0.1578 0.3302) (layers "F.Cu" "F.Paste" "F.Mask")
      (net 255 "unconnected-(U4C-DPSRC_ML1_N-PadN1)") (pinfunction "DPSRC_ML1_N") (pintype "output+no_connect"))
    (pad "N2" smd circle (at -4.6 0.46 270) (size 0.254 0.254) (layers "F.Cu" "F.Paste" "F.Mask")
      (net 256 "unconnected-(U4C-DPSRC_ML1_P-PadN2)") (pinfunction "DPSRC_ML1_P") (pintype "output+no_connect"))
    (pad "N4" smd circle (at -3.9 0.65 270) (size 0.254 0.254) (layers "F.Cu" "F.Paste" "F.Mask")
      (net 176 "Net-(U4C-DPSNK1_DDC_DATA)") (pinfunction "DPSNK1_DDC_DATA") (pintype "passive"))
    (pad "N5" smd circle (at -3.25 0.65 270) (size 0.254 0.254) (layers "F.Cu" "F.Paste" "F.Mask")
      (net 1 "GND") (pinfunction "VSS_ANA") (pintype "passive"))
    (pad "N6" smd circle (at -2.6 0.65 270) (size 0.254 0.254) (layers "F.Cu" "F.Paste" "F.Mask")
      (net 191 "Net-(U4C-DPSRC_RBIAS)") (pinfunction "DPSRC_RBIAS") (pintype "passive"))
    (pad "N8" smd circle (at -1.95 0.65 270) (size 0.254 0.254) (layers "F.Cu" "F.Paste" "F.Mask")
      (net 1 "GND") (pinfunction "VSS") (pintype "passive"))
    (pad "N9" smd circle (at -1.3 0.65 270) (size 0.254 0.254) (layers "F.Cu" "F.Paste" "F.Mask")
      (net 1 "GND") (pinfunction "VSS") (pintype "passive"))
    (pad "N11" smd circle (at -0.65 0.65 270) (size 0.254 0.254) (layers "F.Cu" "F.Paste" "F.Mask")
      (net 1 "GND") (pinfunction "VSS") (pintype "passive"))
    (pad "N12" smd circle (at 0 0.65 270) (size 0.254 0.254) (layers "F.Cu" "F.Paste" "F.Mask")
      (net 1 "GND") (pinfunction "VSS") (pintype "passive"))
    (pad "N13" smd circle (at 0.65 0.65 270) (size 0.254 0.254) (layers "F.Cu" "F.Paste" "F.Mask")
      (net 1 "GND") (pinfunction "VSS") (pintype "passive"))
    (pad "N15" smd circle (at 1.3 0.65 270) (size 0.254 0.254) (layers "F.Cu" "F.Paste" "F.Mask")
      (net 1 "GND") (pinfunction "FUSE_VQPS_128") (pintype "passive"))
    (pad "N16" smd circle (at 1.95 0.65 270) (size 0.254 0.254) (layers "F.Cu" "F.Paste" "F.Mask")
      (net 189 "Net-(U4B-PCIE_RBIAS)") (pinfunction "PCIE_RBIAS") (pintype "input"))
    (pad "N18" smd circle (at 2.6 0.65 270) (size 0.254 0.254) (layers "F.Cu" "F.Paste" "F.Mask")
      (net 108 "Net-(C56-Pad2)") (pinfunction "VCC0P9_ANA_PCIE_2") (pintype "passive"))
    (pad "N19" smd circle (at 3.25 0.65 270) (size 0.254 0.254) (layers "F.Cu" "F.Paste" "F.Mask")
      (net 108 "Net-(C56-Pad2)") (pinfunction "VCC0P9_ANA_PCIE_1") (pintype "passive"))
    (pad "N20" smd circle (at 3.9 0.65 270) (size 0.254 0.254) (layers "F.Cu" "F.Paste" "F.Mask")
      (net 1 "GND") (pinfunction "VSS_ANA") (pintype "passive"))
    (pad "N22" smd circle (at 4.6 0.46 270) (size 0.254 0.254) (layers "F.Cu" "F.Paste" "F.Mask")
      (net 1 "GND") (pinfunction "VSS_ANA") (pintype "passive"))
    (pad "N23" smd oval (at 5.06 0.46) (size 0.1578 0.3302) (layers "F.Cu" "F.Paste" "F.Mask")
      (net 1 "GND") (pinfunction "VSS_ANA") (pintype "passive"))
    (pad "P1" smd oval (at -5.06 0.92) (size 0.1578 0.3302) (layers "F.Cu" "F.Paste" "F.Mask")
      (net 1 "GND") (pinfunction "VSS_ANA") (pintype "passive"))
    (pad "P2" smd circle (at -4.6 0.92 270) (size 0.254 0.254) (layers "F.Cu" "F.Paste" "F.Mask")
      (net 1 "GND") (pinfunction "VSS_ANA") (pintype "passive"))
    (pad "P22" smd circle (at 4.6 0.92 270) (size 0.254 0.254) (layers "F.Cu" "F.Paste" "F.Mask")
      (net 77 "/TB Controller/TX1_N") (pinfunction "PCIE_TX1_N") (pintype "input"))
    (pad "P23" smd oval (at 5.06 0.92) (size 0.1578 0.3302) (layers "F.Cu" "F.Paste" "F.Mask")
      (net 81 "/TB Controller/TX1_P") (pinfunction "PCIE_TX1_P") (pintype "input"))
    (pad "R1" smd oval (at -5.06 1.38) (size 0.1578 0.3302) (layers "F.Cu" "F.Paste" "F.Mask")
      (net 257 "unconnected-(U4C-DPSRC_ML0_N-PadR1)") (pinfunction "DPSRC_ML0_N") (pintype "output+no_connect"))
    (pad "R2" smd circle (at -4.6 1.38 270) (size 0.254 0.254) (layers "F.Cu" "F.Paste" "F.Mask")
      (net 258 "unconnected-(U4C-DPSRC_ML0_P-PadR2)") (pinfunction "DPSRC_ML0_P") (pintype "output+no_connect"))
    (pad "R4" smd circle (at -3.9 1.3 270) (size 0.254 0.254) (layers "F.Cu" "F.Paste" "F.Mask")
      (net 173 "Net-(U4C-DPSNK0_DDC_DATA)") (pinfunction "DPSNK0_DDC_DATA") (pintype "passive"))
    (pad "R5" smd circle (at -3.25 1.3 270) (size 0.254 0.254) (layers "F.Cu" "F.Paste" "F.Mask")
      (net 1 "GND") (pinfunction "VSS_ANA") (pintype "passive"))
    (pad "R6" smd circle (at -2.6 1.3 270) (size 0.254 0.254) (layers "F.Cu" "F.Paste" "F.Mask")
      (net 111 "Net-(U4A-VCC3P3_LC)") (pinfunction "VCC3P3_LC") (pintype "power_in"))
    (pad "R8" smd circle (at -1.95 1.3 270) (size 0.254 0.254) (layers "F.Cu" "F.Paste" "F.Mask")
      (net 107 "Net-(C54-Pad2)") (pinfunction "VCC0P9_CIO") (pintype "passive"))
    (pad "R9" smd circle (at -1.3 1.3 270) (size 0.254 0.254) (layers "F.Cu" "F.Paste" "F.Mask")
      (net 107 "Net-(C54-Pad2)") (pinfunction "VCC0P9_CIO") (pintype "passive"))
    (pad "R11" smd circle (at -0.65 1.3 270) (size 0.254 0.254) (layers "F.Cu" "F.Paste" "F.Mask")
      (net 107 "Net-(C54-Pad2)") (pinfunction "VCC0P9_CIO") (pintype "power_in"))
    (pad "R12" smd circle (at 0 1.3 270) (size 0.254 0.254) (layers "F.Cu" "F.Paste" "F.Mask")
      (net 107 "Net-(C54-Pad2)") (pinfunction "VCC0P9_CIO") (pintype "passive"))
    (pad "R13" smd circle (at 0.65 1.3 270) (size 0.254 0.254) (layers "F.Cu" "F.Paste" "F.Mask")
      (net 114 "Net-(U4A-VCC3P3_S0)") (pinfunction "VCC3P3_S0") (pintype "power_in"))
    (pad "R15" smd circle (at 1.3 1.3 270) (size 0.254 0.254) (layers "F.Cu" "F.Paste" "F.Mask")
      (net 105 "Net-(C51-Pad2)") (pinfunction "VCC0P9_USB") (pintype "power_in"))
    (pad "R16" smd circle (at 1.95 1.3 270) (size 0.254 0.254) (layers "F.Cu" "F.Paste" "F.Mask")
      (net 105 "Net-(C51-Pad2)") (pinfunction "VCC0P9_USB") (pintype "passive"))
    (pad "R18" smd circle (at 2.6 1.3 270) (size 0.254 0.254) (layers "F.Cu" "F.Paste" "F.Mask")
      (net 1 "GND") (pinfunction "VSS_ANA") (pintype "passive"))
    (pad "R19" smd circle (at 3.25 1.3 270) (size 0.254 0.254) (layers "F.Cu" "F.Paste" "F.Mask")
      (net 1 "GND") (pinfunction "VSS_ANA") (pintype "passive"))
    (pad "R20" smd circle (at 3.9 1.3 270) (size 0.254 0.254) (layers "F.Cu" "F.Paste" "F.Mask")
      (net 1 "GND") (pinfunction "VSS_ANA") (pintype "passive"))
    (pad "R22" smd circle (at 4.6 1.38 270) (size 0.254 0.254) (layers "F.Cu" "F.Paste" "F.Mask")
      (net 1 "GND") (pinfunction "VSS_ANA") (pintype "passive"))
    (pad "R23" smd oval (at 5.06 1.38) (size 0.1578 0.3302) (layers "F.Cu" "F.Paste" "F.Mask")
      (net 1 "GND") (pinfunction "VSS_ANA") (pintype "passive"))
    (pad "T1" smd oval (at -5.06 1.84) (size 0.1578 0.3302) (layers "F.Cu" "F.Paste" "F.Mask")
      (net 1 "GND") (pinfunction "VSS_ANA") (pintype "passive"))
    (pad "T2" smd circle (at -4.6 1.84 270) (size 0.254 0.254) (layers "F.Cu" "F.Paste" "F.Mask")
      (net 1 "GND") (pinfunction "VSS_ANA") (pintype "passive"))
    (pad "T4" smd circle (at -3.9 1.95 270) (size 0.254 0.254) (layers "F.Cu" "F.Paste" "F.Mask")
      (net 180 "Net-(U4D-TCK)") (pinfunction "TCK") (pintype "input"))
    (pad "T5" smd circle (at -3.25 1.95 270) (size 0.254 0.254) (layers "F.Cu" "F.Paste" "F.Mask")
      (net 1 "GND") (pinfunction "VSS_ANA") (pintype "passive"))
    (pad "T6" smd circle (at -2.6 1.95 270) (size 0.254 0.254) (layers "F.Cu" "F.Paste" "F.Mask")
      (net 1 "GND") (pinfunction "VSS") (pintype "passive"))
    (pad "T8" smd circle (at -1.95 1.95 270) (size 0.254 0.254) (layers "F.Cu" "F.Paste" "F.Mask")
      (net 1 "GND") (pinfunction "VSS") (pintype "passive"))
    (pad "T9" smd circle (at -1.3 1.95 270) (size 0.254 0.254) (layers "F.Cu" "F.Paste" "F.Mask")
      (net 1 "GND") (pinfunction "VSS") (pintype "passive"))
    (pad "T11" smd circle (at -0.65 1.95 270) (size 0.254 0.254) (layers "F.Cu" "F.Paste" "F.Mask")
      (net 106 "Net-(C53-Pad2)") (pinfunction "VCC0P9_DP") (pintype "passive"))
    (pad "T12" smd circle (at 0 1.95 270) (size 0.254 0.254) (layers "F.Cu" "F.Paste" "F.Mask")
      (net 106 "Net-(C53-Pad2)") (pinfunction "VCC0P9_DP") (pintype "passive"))
    (pad "T13" smd circle (at 0.65 1.95 270) (size 0.254 0.254) (layers "F.Cu" "F.Paste" "F.Mask")
      (net 1 "GND") (pinfunction "VSS") (pintype "passive"))
    (pad "T15" smd circle (at 1.3 1.95 270) (size 0.254 0.254) (layers "F.Cu" "F.Paste" "F.Mask")
      (net 1 "GND") (pinfunction "VSS") (pintype "passive"))
    (pad "T16" smd circle (at 1.95 1.95 270) (size 0.254 0.254) (layers "F.Cu" "F.Paste" "F.Mask")
      (net 1 "GND") (pinfunction "VSS") (pintype "passive"))
    (pad "T18" smd circle (at 2.6 1.95 270) (size 0.254 0.254) (layers "F.Cu" "F.Paste" "F.Mask")
      (net 1 "GND") (pinfunction "VSS") (pintype "passive"))
    (pad "T19" smd circle (at 3.25 1.95 270) (size 0.254 0.254) (layers "F.Cu" "F.Paste" "F.Mask")
      (net 73 "/TB Controller/PCIE_CLK_JHL_N") (pinfunction "PCIE_REFCLK_100_IN_N") (pintype "input"))
    (pad "T20" smd circle (at 3.9 1.95 270) (size 0.254 0.254) (layers "F.Cu" "F.Paste" "F.Mask")
      (net 1 "GND") (pinfunction "VSS_ANA") (pintype "passive"))
    (pad "T22" smd circle (at 4.6 1.84 270) (size 0.254 0.254) (layers "F.Cu" "F.Paste" "F.Mask")
      (net 49 "PCIE_RX1_N") (pinfunction "PCIE_RX1_N") (pintype "input"))
    (pad "T23" smd oval (at 5.06 1.84) (size 0.1578 0.3302) (layers "F.Cu" "F.Paste" "F.Mask")
      (net 48 "PCIE_RX1_P") (pinfunction "PCIE_RX1_P") (pintype "input"))
    (pad "U1" smd oval (at -5.06 2.3) (size 0.1578 0.3302) (layers "F.Cu" "F.Paste" "F.Mask")
      (net 59 "I2C1_SDA") (pinfunction "GPIO_0") (pintype "bidirectional"))
    (pad "U2" smd circle (at -4.6 2.3 270) (size 0.254 0.254) (layers "F.Cu" "F.Paste" "F.Mask")
      (net 57 "I2C1_SCL") (pinfunction "GPIO_1") (pintype "bidirectional"))
    (pad "U22" smd circle (at 4.6 2.3 270) (size 0.254 0.254) (layers "F.Cu" "F.Paste" "F.Mask")
      (net 1 "GND") (pinfunction "VSS_ANA") (pintype "passive"))
    (pad "U23" smd oval (at 5.06 2.3) (size 0.1578 0.3302) (layers "F.Cu" "F.Paste" "F.Mask")
      (net 1 "GND") (pinfunction "VSS_ANA") (pintype "passive"))
    (pad "V1" smd oval (at -5.06 2.76) (size 0.1578 0.3302) (layers "F.Cu" "F.Paste" "F.Mask")
      (net 64 "/TB Controller/FLASH_WP") (pinfunction "GPIO_2") (pintype "bidirectional"))
    (pad "V2" smd circle (at -4.6 2.76 270) (size 0.254 0.254) (layers "F.Cu" "F.Paste" "F.Mask")
      (net 192 "Net-(U4C-GPIO_3)") (pinfunction "GPIO_3") (pintype "bidirectional"))
    (pad "V4" smd circle (at -3.9 2.6 270) (size 0.254 0.254) (layers "F.Cu" "F.Paste" "F.Mask")
      (net 179 "Net-(U4D-TMS)") (pinfunction "TMS") (pintype "input"))
    (pad "V5" smd circle (at -3.25 2.6 270) (size 0.254 0.254) (layers "F.Cu" "F.Paste" "F.Mask")
      (net 1 "GND") (pinfunction "VSS_ANA") (pintype "passive"))
    (pad "V6" smd circle (at -2.6 2.6 270) (size 0.254 0.254) (layers "F.Cu" "F.Paste" "F.Mask")
      (net 1 "GND") (pinfunction "VSS_ANA") (pintype "passive"))
    (pad "V8" smd circle (at -1.95 2.6 270) (size 0.254 0.254) (layers "F.Cu" "F.Paste" "F.Mask")
      (net 1 "GND") (pinfunction "VSS_ANA") (pintype "passive"))
    (pad "V9" smd circle (at -1.3 2.6 270) (size 0.254 0.254) (layers "F.Cu" "F.Paste" "F.Mask")
      (net 1 "GND") (pinfunction "VSS_ANA") (pintype "passive"))
  )
)
